# S9S_MB_2U (Grand Teton) — schematic netlist excerpt (pin names and nets, part order shuffled) for the footprints in the layout excerpt that follows; sources: Cadence DE-HDL packaged netlist, KiCad conversion of 03242023_DA0F0TMBIJ0_F0T_Motherboard_J_brd_V01_OCP.brd

C339  Q_CAP  47UF 4V 20% X6S  pkg C0805  page 78 : A = PVCCIN_CPU1 ; B = GND
R1015  Q_RES  0 5% EMPTY  pkg 0402LF  page 209 : A = CLK_25M_PCH_CPU0_DN ; B = CLK_25M_NSSC_CPU0_DN
R680  Q_RES  499 1% CHIP  pkg 0402LF  page 229 : A = PVNN_TERM_CPU0 ; B = I3C_SPD_DDRABCD_CPU0_SDA

(kicad_pcb
	(version 20260206)
	(generator "pcbnew")
	(generator_version "10.0")
	(general
		(thickness 1.6)
		(legacy_teardrops no)
	)
	(paper "A4")
	(title_block
		(title "03242023_DA0F0TMBIJ0_F0T_Motherboard_J_brd_V01_OCP.brd")
		(comment 1 "Grand Teton / footprints 4971-4973 of 6105")
	)
	(layers
		(0 "F.Cu" signal "TOP")
		(4 "In1.Cu" signal "GND")
		(6 "In2.Cu" signal "IN1")
		(8 "In3.Cu" signal "GND1")
		(10 "In4.Cu" signal "IN2")
		(12 "In5.Cu" signal "GND2")
		(14 "In6.Cu" signal "IN3")
		(16 "In7.Cu" signal "GND3")
		(18 "In8.Cu" signal "VCC")
		(20 "In9.Cu" signal "VCC1")
		(22 "In10.Cu" signal "GND4")
		(24 "In11.Cu" signal "IN4")
		(26 "In12.Cu" signal "GND5")
		(28 "In13.Cu" signal "IN5")
		(30 "In14.Cu" signal "GND6")
		(32 "In15.Cu" signal "IN6")
		(34 "In16.Cu" signal "GND7")
		(2 "B.Cu" signal "BOTTOM")
		(9 "F.Adhes" user "F.Adhesive")
		(11 "B.Adhes" user "B.Adhesive")
		(13 "F.Paste" user "Package Geometry/Pastemask Top")
		(15 "B.Paste" user "Package Geometry/Pastemask Bottom")
		(5 "F.SilkS" user "Ref Des/Silkscreen Top")
		(7 "B.SilkS" user "Ref Des/Silkscreen Bottom")
		(1 "F.Mask" user "Board Geometry/Soldermask Top")
		(3 "B.Mask" user "Board Geometry/Soldermask Bottom")
		(17 "Dwgs.User" user "User.Drawings")
		(19 "Cmts.User" user "User.Comments")
		(21 "Eco1.User" user "User.Eco1")
		(23 "Eco2.User" user "User.Eco2")
		(25 "Edge.Cuts" user "Board Geometry/Outline")
		(27 "Margin" user)
		(31 "F.CrtYd" user "Package Geometry/Place Bound Top")
		(29 "B.CrtYd" user "Package Geometry/Place Bound Bottom")
		(35 "F.Fab" user "Ref Des/Assembly Top")
		(33 "B.Fab" user "Ref Des/Assembly Bottom")
	)
	(footprint ""
		(layer "B.Cu")
		(at 338.422234 -136.479534)
		(property "Reference" "R1015"
			(at 0 0 0)
			(layer "B.SilkS")
			(hide yes)
			(effects
				(font
					(size 1.27 1.27)
				)
				(justify mirror)
			)
		)
		(property "Value" ""
			(at 0 0 0)
			(layer "B.Fab")
			(effects
				(font
					(size 1.27 1.27)
				)
				(justify mirror)
			)
		)
		(duplicate_pad_numbers_are_jumpers no)
		(fp_line
			(start -0.7874 -0.4064)
			(end -0.7874 0.4064)
			(stroke
				(width 0.1524)
				(type default)
			)
			(layer "B.SilkS")
		)
		(fp_line
			(start -0.7874 0.4064)
			(end 0.7874 0.4064)
			(stroke
				(width 0.1524)
				(type default)
			)
			(layer "B.SilkS")
		)
		(fp_line
			(start -0.630174 -0.4064)
			(end -0.7874 -0.4064)
			(stroke
				(width 0.1524)
				(type default)
			)
			(layer "B.SilkS")
		)
		(fp_line
			(start 0.7874 -0.4064)
			(end -0.195834 -0.4064)
			(stroke
				(width 0.1524)
				(type default)
			)
			(layer "B.SilkS")
		)
		(fp_line
			(start 0.7874 -0.208534)
			(end 0.7874 -0.4064)
			(stroke
				(width 0.1524)
				(type default)
			)
			(layer "B.SilkS")
		)
		(fp_line
			(start 0.7874 0.4064)
			(end 0.7874 0.220726)
			(stroke
				(width 0.1524)
				(type default)
			)
			(layer "B.SilkS")
		)
		(fp_line
			(start -0.67945 -0.3048)
			(end -0.67945 0.3048)
			(stroke
				(width 0.1)
				(type default)
			)
			(layer "B.Fab")
		)
		(fp_line
			(start -0.67945 0.3048)
			(end -0.120396 0.3048)
			(stroke
				(width 0.1)
				(type default)
			)
			(layer "B.Fab")
		)
		(fp_line
			(start -0.12065 -0.3048)
			(end -0.67945 -0.3048)
			(stroke
				(width 0.1)
				(type default)
			)
			(layer "B.Fab")
		)
		(fp_line
			(start -0.12065 -0.2794)
			(end -0.12065 -0.3048)
			(stroke
				(width 0.1)
				(type default)
			)
			(layer "B.Fab")
		)
		(fp_line
			(start -0.120396 0.2794)
			(end 0.12065 0.2794)
			(stroke
				(width 0.1)
				(type default)
			)
			(layer "B.Fab")
		)
		(fp_line
			(start -0.120396 0.3048)
			(end -0.120396 0.2794)
			(stroke
				(width 0.1)
				(type default)
			)
			(layer "B.Fab")
		)
		(fp_line
			(start 0.12065 -0.305054)
			(end 0.12065 -0.2794)
			(stroke
				(width 0.1)
				(type default)
			)
			(layer "B.Fab")
		)
		(fp_line
			(start 0.12065 -0.2794)
			(end -0.12065 -0.2794)
			(stroke
				(width 0.1)
				(type default)
			)
			(layer "B.Fab")
		)
		(fp_line
			(start 0.12065 0.2794)
			(end 0.12065 0.3048)
			(stroke
				(width 0.1)
				(type default)
			)
			(layer "B.Fab")
		)
		(fp_line
			(start 0.12065 0.3048)
			(end 0.67945 0.3048)
			(stroke
				(width 0.1)
				(type default)
			)
			(layer "B.Fab")
		)
		(fp_line
			(start 0.67945 -0.305054)
			(end 0.12065 -0.305054)
			(stroke
				(width 0.1)
				(type default)
			)
			(layer "B.Fab")
		)
		(fp_line
			(start 0.67945 0.3048)
			(end 0.67945 -0.305054)
			(stroke
				(width 0.1)
				(type default)
			)
			(layer "B.Fab")
		)
		(pad "1" smd rect
			(at 0.40005 0)
			(size 0.4572 0.508)
			(layers "B.Cu" "B.Mask" "B.Paste")
			(net "CLK_25M_PCH_CPU0_DN")
		)
		(pad "2" smd rect
			(at -0.40005 0)
			(size 0.4572 0.508)
			(layers "B.Cu" "B.Mask" "B.Paste")
			(net "CLK_25M_NSSC_CPU0_DN")
		)
	)
	(footprint ""
		(layer "B.Cu")
		(at 107.457494 -248.49836 -90)
		(property "Reference" "C339"
			(at 0 0 90)
			(layer "B.SilkS")
			(hide yes)
			(effects
				(font
					(size 1.27 1.27)
				)
				(justify mirror)
			)
		)
		(property "Value" ""
			(at 0 0 90)
			(layer "B.Fab")
			(effects
				(font
					(size 1.27 1.27)
				)
				(justify mirror)
			)
		)
		(duplicate_pad_numbers_are_jumpers no)
		(fp_line
			(start -1.524 0.762)
			(end 1.524 0.762)
			(stroke
				(width 0.1524)
				(type default)
			)
			(layer "B.SilkS")
		)
		(fp_line
			(start 1.524 0.762)
			(end 1.524 -0.762)
			(stroke
				(width 0.1524)
				(type default)
			)
			(layer "B.SilkS")
		)
		(fp_line
			(start -1.524 -0.762)
			(end -1.524 0.762)
			(stroke
				(width 0.1524)
				(type default)
			)
			(layer "B.SilkS")
		)
		(fp_line
			(start 1.524 -0.762)
			(end -1.524 -0.762)
			(stroke
				(width 0.1524)
				(type default)
			)
			(layer "B.SilkS")
		)
		(fp_line
			(start -1.1049 0.724916)
			(end -1.1049 -0.724916)
			(stroke
				(width 0.1)
				(type default)
			)
			(layer "B.Fab")
		)
		(fp_line
			(start 1.1049 0.724916)
			(end -1.1049 0.724916)
			(stroke
				(width 0.1)
				(type default)
			)
			(layer "B.Fab")
		)
		(fp_line
			(start -1.1049 -0.724916)
			(end 1.1049 -0.724916)
			(stroke
				(width 0.1)
				(type default)
			)
			(layer "B.Fab")
		)
		(fp_line
			(start 1.1049 -0.724916)
			(end 1.1049 0.724916)
			(stroke
				(width 0.1)
				(type default)
			)
			(layer "B.Fab")
		)
		(pad "1" smd rect
			(at 0.889 0 270)
			(size 1.016 1.27)
			(layers "B.Cu" "B.Mask" "B.Paste")
			(net "PVCCIN_CPU1")
		)
		(pad "2" smd rect
			(at -0.889 0 270)
			(size 1.016 1.27)
			(layers "B.Cu" "B.Mask" "B.Paste")
			(net "GND")
		)
	)
	(footprint ""
		(layer "B.Cu")
		(at 338.045552 -190.756286 -90)
		(property "Reference" "R680"
			(at 0 0 90)
			(layer "B.SilkS")
			(hide yes)
			(effects
				(font
					(size 1.27 1.27)
				)
				(justify mirror)
			)
		)
		(property "Value" ""
			(at 0 0 90)
			(layer "B.Fab")
			(effects
				(font
					(size 1.27 1.27)
				)
				(justify mirror)
			)
		)
		(duplicate_pad_numbers_are_jumpers no)
		(fp_line
			(start -0.7874 0.4064)
			(end 0.7874 0.4064)
			(stroke
				(width 0.1524)
				(type default)
			)
			(layer "B.SilkS")
		)
		(fp_line
			(start 0.7874 0.4064)
			(end 0.7874 -0.4064)
			(stroke
				(width 0.1524)
				(type default)
			)
			(layer "B.SilkS")
		)
		(fp_line
			(start -0.7874 -0.4064)
			(end -0.7874 0.4064)
			(stroke
				(width 0.1524)
				(type default)
			)
			(layer "B.SilkS")
		)
		(fp_line
			(start 0.7874 -0.4064)
			(end -0.7874 -0.4064)
			(stroke
				(width 0.1524)
				(type default)
			)
			(layer "B.SilkS")
		)
		(fp_line
			(start -0.67945 0.3048)
			(end -0.120396 0.3048)
			(stroke
				(width 0.1)
				(type default)
			)
			(layer "B.Fab")
		)
		(fp_line
			(start -0.120396 0.3048)
			(end -0.120396 0.2794)
			(stroke
				(width 0.1)
				(type default)
			)
			(layer "B.Fab")
		)
		(fp_line
			(start 0.12065 0.3048)
			(end 0.67945 0.3048)
			(stroke
				(width 0.1)
				(type default)
			)
			(layer "B.Fab")
		)
		(fp_line
			(start 0.67945 0.3048)
			(end 0.67945 -0.305054)
			(stroke
				(width 0.1)
				(type default)
			)
			(layer "B.Fab")
		)
		(fp_line
			(start -0.120396 0.2794)
			(end 0.12065 0.2794)
			(stroke
				(width 0.1)
				(type default)
			)
			(layer "B.Fab")
		)
		(fp_line
			(start 0.12065 0.2794)
			(end 0.12065 0.3048)
			(stroke
				(width 0.1)
				(type default)
			)
			(layer "B.Fab")
		)
		(fp_line
			(start -0.12065 -0.2794)
			(end -0.12065 -0.3048)
			(stroke
				(width 0.1)
				(type default)
			)
			(layer "B.Fab")
		)
		(fp_line
			(start 0.12065 -0.2794)
			(end -0.12065 -0.2794)
			(stroke
				(width 0.1)
				(type default)
			)
			(layer "B.Fab")
		)
		(fp_line
			(start -0.67945 -0.3048)
			(end -0.67945 0.3048)
			(stroke
				(width 0.1)
				(type default)
			)
			(layer "B.Fab")
		)
		(fp_line
			(start -0.12065 -0.3048)
			(end -0.67945 -0.3048)
			(stroke
				(width 0.1)
				(type default)
			)
			(layer "B.Fab")
		)
		(fp_line
			(start 0.12065 -0.305054)
			(end 0.12065 -0.2794)
			(stroke
				(width 0.1)
				(type default)
			)
			(layer "B.Fab")
		)
		(fp_line
			(start 0.67945 -0.305054)
			(end 0.12065 -0.305054)
			(stroke
				(width 0.1)
				(type default)
			)
			(layer "B.Fab")
		)
		(pad "1" smd circle
			(at 0.40005 0 90)
			(size 0 0)
			(layers "B.Cu" "B.Mask" "B.Paste")
			(net "PVNN_TERM_CPU0")
		)
		(pad "2" smd circle
			(at -0.40005 0 90)
			(size 0 0)
			(layers "B.Cu" "B.Mask" "B.Paste")
			(net "I3C_SPD_DDRABCD_CPU0_SDA")
		)
	)
)
